# T6G (Grand Teton) — schematic parts with pin connectivity, parts 8082–8082 of 8303; source: Cadence DE-HDL packaged netlist (pstxprt.dat, pstxnet.dat, pstchip.dat)

U26  GENOA_SP5  SOCKET6096_13568-001 IO  pkg SOCKET6096_93-4X120-45XA  page 37  (pins 1-336 of 6096)
  A3  VSS_A3  POWER  = GND
  A4  \i3c3_scl||i2c3_scl||spd3_scl||agpio151\  BI  = NC
  A5  \i3c1_sda||i2c1_sda||spd1_sda||agpio148\  BI  = I3C_1_SPD_DDRGL_CPU1_R_SDA
  A7  GPP_CLK01N  OUT  = CLK_100M_CPU1_CLK01_R_DN
  A8  GPP_CLK01P  OUT  = CLK_100M_CPU1_CLK01_R_DP
  A9  VSS_A9  POWER  = GND
  A10  GPP_CLK03P  OUT  = CLK_100M_CPU1_CLK03_R_DP
  A11  GPP_CLK03N  OUT  = CLK_100M_CPU1_CLK03_R_DN
  A13  \agpio258||sgpio2_clk||clk_req02_l\  BI  = NC
  A14  \agpio256||sgpio0_clk\  BI  = NC
  A15  VSS_A15  POWER  = GND
  A16  TMS  IN  = JTAG_CPU1_TMS
  A17  TRST_L  IN  = JTAG_CPU1_TRST_N
  A19  \refclk100ssc_p||gpp_clk10p\  BI  = CLK_100M_REF_IN_DP
  A20  \refclk100ssc_n||gpp_clk10n\  BI  = CLK_100M_REF_IN_DN
  A21  VSS_A21  POWER  = GND
  A22  SVD0  BI  = SVID_PVDDCR_CPU0_P1_SVD
  A23  SVC0  OUT  = SVID_PVDDCR_CPU0_P1_SVC
  A25  USB00_DN  BI  = NC_CPU1_USB2_USB00_DN
  A26  USB00_DP  BI  = NC_CPU1_USB2_USB00_DP
  A27  VSS_A27  POWER  = GND
  A28  USB01_DP  BI  = NC_CPU1_USB2_USB01_DP
  A29  USB01_DN  BI  = NC_CPU1_USB2_USB01_DN
  A31  RSVD_A31  TRI  = NC
  A32  \az_sdout||sw_mdata2\  OUT  = NC_CPU1_AZ_SDOUT
  A33  \az_sdin2||sw_mdata0\  OUT  = NC_CPU1_AZ_SDIN2
  A34  \az_rst_l||sw_mdata1\  OUT  = NC_CPU1_AZ_RST_N
  A35  RSVD_A35  TRI  = NC
  A41  RSVD_A41  TRI  = NC
  A42  RSVD_A42  TRI  = NC
  A43  VSS_A43  POWER  = GND
  A44  VSS_A44  POWER  = GND
  A45  RSVD_A45  TRI  = NC
  A47  VSS_A47  POWER  = GND
  A48  RSVD_A48  TRI  = NC
  A49  VSS_A49  POWER  = GND
  A50  RSVD_A50  TRI  = NC
  A51  RSVD_A51  TRI  = NC
  A53  VSS_A53  POWER  = GND
  A54  RSVD_A54  TRI  = NC
  A55  RSVD_A55  TRI  = NC
  A56  RSVD_A56  TRI  = NC
  A57  RSVD_A57  TRI  = NC
  A59  RSVD_A59  TRI  = NC
  A60  RSVD_A60  TRI  = NC
  A61  VSS_A61  POWER  = GND
  A62  BP3  OUT  = CPU1_BP3
  A63  BP2  OUT  = CPU1_BP2
  A65  XTRIG_L7  OUT  = CPU1_XTRIG_R2_L7
  A66  XTRIG_L6  OUT  = CPU1_XTRIG_R2_L6
  A67  VSS_A67  POWER  = GND
  A68  ALERT_L  OUT  = APML_CPU1_ALERT_N
  A69  PROCHOT_L  IN  = CPU1_PROCHOT_N
  A71  \i3c0_scl||i2c0_scl||spd0_scl||smbus0_scl||agpio145\  BI  = I3C_0_SPD_DDRAF_CPU1_R_SCL
  A72  VSS_A72  POWER  = GND
  A73  VSS_A73  POWER  = GND
  AA1  VSS_AA1  POWER  = GND
  AA2  MGA_DATA20  BI  = M_G_CPU1_SA_DQ<20>
  AA3  MGA_DQS_H7  BI  = M_G_CPU1_SA_DQS_DP<7>
  AA4  VSS_AA4  POWER  = GND
  AA5  MKA_DATA20  BI  = M_K_CPU1_SA_DQ<20>
  AA6  VSS_AA6  POWER  = GND
  AA7  MKA_DQS_H7  BI  = M_K_CPU1_SA_DQS_DP<7>
  AA8  VSS_AA8  POWER  = GND
  AA9  MLA_DATA20  BI  = M_L_CPU1_SA_DQ<20>
  AA10  MLA_DQS_H7  BI  = M_L_CPU1_SA_DQS_DP<7>
  AA11  VSS_AA11  POWER  = GND
  AA12  MHA_DATA20  BI  = M_H_CPU1_SA_DQ<20>
  AA13  VSS_AA13  POWER  = GND
  AA14  MHA_DQS_H7  BI  = M_H_CPU1_SA_DQS_DP<7>
  AA15  VSS_AA15  POWER  = GND
  AA16  MJA_DATA20  BI  = M_J_CPU1_SA_DQ<20>
  AA17  MJA_DQS_H7  BI  = M_J_CPU1_SA_DQS_DP<7>
  AA18  VSS_AA18  POWER  = GND
  AA19  MIA_DATA20  BI  = M_I_CPU1_SA_DQ<20>
  AA20  VSS_AA20  POWER  = GND
  AA21  MIA_DQS_H7  BI  = M_I_CPU1_SA_DQS_DP<7>
  AA22  VDDCR_SOC_AA22  POWER  = PVDDCR_SOC_P1
  AA23  TEST6_X3D4  OUT  = TP_CPU1_TEST6_X3D4
  AA24  TEST5_IOD  TRI  = TP_CPU1_TEST5_IOD
  AA25  TEST4_IOD  TRI  = TP_CPU1_TEST4_IOD
  AA26  TEST5_CCD7  TRI  = TP_CPU1_TEST5_CCD7
  AA27  TEST4_CCD7  TRI  = TP_CPU1_TEST4_CCD7
  AA28  TEST4_CCD11  TRI  = TP_CPU1_TEST4_CCD11
  AA29  TEST6_X3D2  OUT  = TP_CPU1_TEST6_X3D2
  AA30  TEST4_CCD3  TRI  = TP_CPU1_TEST4_CCD3
  AA31  VSS_AA31  POWER  = GND
  AA32  G2_RXN11  IN  = GMI_CPU0_G0_CPU1_G2_TX_DN<4>
  AA33  G2_RXP11  IN  = GMI_CPU0_G0_CPU1_G2_TX_DP<4>
  AA34  VSS_AA34  POWER  = GND
  AA35  VSS_AA35  POWER  = GND
  AA36  VSS_AA36  POWER  = GND
  AA40  VSS_AA40  POWER  = GND
  AA41  VSS_AA41  POWER  = GND
  AA42  VSS_AA42  POWER  = GND
  AA43  G0_TXP4  OUT  = GMI_CPU1_G0_CPU0_G2_TX_DP<11>
  AA44  G0_TXN4  OUT  = GMI_CPU1_G0_CPU0_G2_TX_DN<11>
  AA45  VSS_AA45  POWER  = GND
  AA46  TEST6_CCD0  OUT  = TP_CPU1_TEST6_CCD0
  AA47  TEST6_X3D0  OUT  = TP_CPU1_TEST6_X3D0
  AA48  TEST4_CCD8  TRI  = TP_CPU1_TEST4_CCD8
  AA49  TEST6_IOD  OUT  = TP_CPU1_TEST6_IOD
  AA50  TEST4_CCD0  TRI  = TP_CPU1_TEST4_CCD0
  AA51  TEST5_CCD0  TRI  = TP_CPU1_TEST5_CCD0
  AA52  TEST4_CCD4  TRI  = TP_CPU1_TEST4_CCD4
  AA53  TEST5_CCD4  TRI  = TP_CPU1_TEST5_CCD4
  AA54  VDDIO_AA54  POWER  = PVDDIO_P1
  AA55  MCA_DQS_H7  BI  = M_C_CPU1_SA_DQS_DP<7>
  AA56  VSS_AA56  POWER  = GND
  AA57  MCA_DATA20  BI  = M_C_CPU1_SA_DQ<20>
  AA58  VSS_AA58  POWER  = GND
  AA59  MDA_DQS_H7  BI  = M_D_CPU1_SA_DQS_DP<7>
  AA60  MDA_DATA20  BI  = M_D_CPU1_SA_DQ<20>
  AA61  VSS_AA61  POWER  = GND
  AA62  MBA_DQS_H7  BI  = M_B_CPU1_SA_DQS_DP<7>
  AA63  VSS_AA63  POWER  = GND
  AA64  MBA_DATA20  BI  = M_B_CPU1_SA_DQ<20>
  AA65  VSS_AA65  POWER  = GND
  AA66  MFA_DQS_H7  BI  = M_F_CPU1_SA_DQS_DP<7>
  AA67  MFA_DATA20  BI  = M_F_CPU1_SA_DQ<20>
  AA68  VSS_AA68  POWER  = GND
  AA69  MEA_DQS_H7  BI  = M_E_CPU1_SA_DQS_DP<7>
  AA70  VSS_AA70  POWER  = GND
  AA71  MEA_DATA20  BI  = M_E_CPU1_SA_DQ<20>
  AA72  VSS_AA72  POWER  = GND
  AA73  MAA_DQS_H7  BI  = M_A_CPU1_SA_DQS_DP<7>
  AA74  MAA_DATA20  BI  = M_A_CPU1_SA_DQ<20>
  AA75  VSS_AA75  POWER  = GND
  AB2  MGA_DATA22  BI  = M_G_CPU1_SA_DQ<22>
  AB3  VSS_AB3  POWER  = GND
  AB4  MGA_DATA21  BI  = M_G_CPU1_SA_DQ<21>
  AB5  VSS_AB5  POWER  = GND
  AB6  MKA_DATA22  BI  = M_K_CPU1_SA_DQ<22>
  AB7  MKA_DATA21  BI  = M_K_CPU1_SA_DQ<21>
  AB8  VSS_AB8  POWER  = GND
  AB9  MLA_DATA22  BI  = M_L_CPU1_SA_DQ<22>
  AB10  VSS_AB10  POWER  = GND
  AB11  MLA_DATA21  BI  = M_L_CPU1_SA_DQ<21>
  AB12  VSS_AB12  POWER  = GND
  AB13  MHA_DATA22  BI  = M_H_CPU1_SA_DQ<22>
  AB14  MHA_DATA21  BI  = M_H_CPU1_SA_DQ<21>
  AB15  VSS_AB15  POWER  = GND
  AB16  MJA_DATA22  BI  = M_J_CPU1_SA_DQ<22>
  AB17  VSS_AB17  POWER  = GND
  AB18  MJA_DATA21  BI  = M_J_CPU1_SA_DQ<21>
  AB19  VSS_AB19  POWER  = GND
  AB20  MIA_DATA22  BI  = M_I_CPU1_SA_DQ<22>
  AB21  MIA_DATA21  BI  = M_I_CPU1_SA_DQ<21>
  AB22  VSS_AB22  POWER  = GND
  AB23  VDDCR_CPU0_AB23  POWER  = PVDDCR_CPU0_P1
  AB24  VDDCR_CPU0_AB24  POWER  = PVDDCR_CPU0_P1
  AB25  VSS_AB25  POWER  = GND
  AB26  VDDCR_CPU0_AB26  POWER  = PVDDCR_CPU0_P1
  AB27  VDDCR_CPU0_AB27  POWER  = PVDDCR_CPU0_P1
  AB28  VSS_AB28  POWER  = GND
  AB29  VDDCR_CPU0_AB29  POWER  = PVDDCR_CPU0_P1
  AB30  VDDCR_CPU0_AB30  POWER  = PVDDCR_CPU0_P1
  AB31  VSS_AB31  POWER  = GND
  AB32  VDDCR_CPU0_AB32  POWER  = PVDDCR_CPU0_P1
  AB33  VDDCR_CPU0_AB33  POWER  = PVDDCR_CPU0_P1
  AB34  VSS_AB34  POWER  = GND
  AB35  G2_RXN13  IN  = GMI_CPU0_G0_CPU1_G2_TX_DN<2>
  AB36  G2_RXP13  IN  = GMI_CPU0_G0_CPU1_G2_TX_DP<2>
  AB37  VSS_AB37  POWER  = GND
  AB39  VSS_AB39  POWER  = GND
  AB40  G0_TXP2  OUT  = GMI_CPU1_G0_CPU0_G2_TX_DP<13>
  AB41  G0_TXN2  OUT  = GMI_CPU1_G0_CPU0_G2_TX_DN<13>
  AB42  VSS_AB42  POWER  = GND
  AB43  VDDCR_CPU0_AB43  POWER  = PVDDCR_CPU0_P1
  AB44  VDDCR_CPU0_AB44  POWER  = PVDDCR_CPU0_P1
  AB45  VSS_AB45  POWER  = GND
  AB46  VDDCR_CPU0_AB46  POWER  = PVDDCR_CPU0_P1
  AB47  VDDCR_CPU0_AB47  POWER  = PVDDCR_CPU0_P1
  AB48  VSS_AB48  POWER  = GND
  AB49  VDDCR_CPU0_AB49  POWER  = PVDDCR_CPU0_P1
  AB50  VDDCR_CPU0_AB50  POWER  = PVDDCR_CPU0_P1
  AB51  VSS_AB51  POWER  = GND
  AB52  VDDCR_CPU0_AB52  POWER  = PVDDCR_CPU0_P1
  AB53  VDDCR_CPU0_AB53  POWER  = PVDDCR_CPU0_P1
  AB54  VSS_AB54  POWER  = GND
  AB55  MCA_DATA21  BI  = M_C_CPU1_SA_DQ<21>
  AB56  MCA_DATA22  BI  = M_C_CPU1_SA_DQ<22>
  AB57  VSS_AB57  POWER  = GND
  AB58  MDA_DATA21  BI  = M_D_CPU1_SA_DQ<21>
  AB59  VSS_AB59  POWER  = GND
  AB60  MDA_DATA22  BI  = M_D_CPU1_SA_DQ<22>
  AB61  VSS_AB61  POWER  = GND
  AB62  MBA_DATA21  BI  = M_B_CPU1_SA_DQ<21>
  AB63  MBA_DATA22  BI  = M_B_CPU1_SA_DQ<22>
  AB64  VSS_AB64  POWER  = GND
  AB65  MFA_DATA21  BI  = M_F_CPU1_SA_DQ<21>
  AB66  VSS_AB66  POWER  = GND
  AB67  MFA_DATA22  BI  = M_F_CPU1_SA_DQ<22>
  AB68  VSS_AB68  POWER  = GND
  AB69  MEA_DATA21  BI  = M_E_CPU1_SA_DQ<21>
  AB70  MEA_DATA22  BI  = M_E_CPU1_SA_DQ<22>
  AB71  VSS_AB71  POWER  = GND
  AB72  MAA_DATA21  BI  = M_A_CPU1_SA_DQ<21>
  AB73  VSS_AB73  POWER  = GND
  AB74  MAA_DATA22  BI  = M_A_CPU1_SA_DQ<22>
  AC1  VSS_AC1  POWER  = GND
  AC2  MGA_DATA24  BI  = M_G_CPU1_SA_DQ<24>
  AC3  MGA_DATA23  BI  = M_G_CPU1_SA_DQ<23>
  AC4  VDDCR_SOC_AC4  POWER  = PVDDCR_SOC_P1
  AC5  MKA_DATA24  BI  = M_K_CPU1_SA_DQ<24>
  AC6  VSS_AC6  POWER  = GND
  AC7  MKA_DATA23  BI  = M_K_CPU1_SA_DQ<23>
  AC8  VSS_AC8  POWER  = GND
  AC9  MLA_DATA24  BI  = M_L_CPU1_SA_DQ<24>
  AC10  MLA_DATA23  BI  = M_L_CPU1_SA_DQ<23>
  AC11  VDDCR_SOC_AC11  POWER  = PVDDCR_SOC_P1
  AC12  MHA_DATA24  BI  = M_H_CPU1_SA_DQ<24>
  AC13  VSS_AC13  POWER  = GND
  AC14  MHA_DATA23  BI  = M_H_CPU1_SA_DQ<23>
  AC15  VSS_AC15  POWER  = GND
  AC16  MJA_DATA24  BI  = M_J_CPU1_SA_DQ<24>
  AC17  MJA_DATA23  BI  = M_J_CPU1_SA_DQ<23>
  AC18  VDDCR_SOC_AC18  POWER  = PVDDCR_SOC_P1
  AC19  MIA_DATA24  BI  = M_I_CPU1_SA_DQ<24>
  AC20  VSS_AC20  POWER  = GND
  AC21  MIA_DATA23  BI  = M_I_CPU1_SA_DQ<23>
  AC22  VSS_AC22  POWER  = GND
  AC23  G2_RXN1  IN  = GMI_CPU0_G0_CPU1_G2_TX_DN<14>
  AC24  G2_RXP1  IN  = GMI_CPU0_G0_CPU1_G2_TX_DP<14>
  AC25  VSS_AC25  POWER  = GND
  AC26  G2_RXN4  IN  = GMI_CPU0_G0_CPU1_G2_TX_DN<11>
  AC27  G2_RXP4  IN  = GMI_CPU0_G0_CPU1_G2_TX_DP<11>
  AC28  VSS_AC28  POWER  = GND
  AC29  G2_RXN7  IN  = GMI_CPU0_G0_CPU1_G2_TX_DN<8>
  AC30  G2_RXP7  IN  = GMI_CPU0_G0_CPU1_G2_TX_DP<8>
  AC31  VSS_AC31  POWER  = GND
  AC32  G2_RXN10  IN  = GMI_CPU0_G0_CPU1_G2_TX_DN<5>
  AC33  G2_RXP10  IN  = GMI_CPU0_G0_CPU1_G2_TX_DP<5>
  AC34  VSS_AC34  POWER  = GND
  AC35  VDDCR_CPU0_AC35  POWER  = PVDDCR_CPU0_P1
  AC36  VDDCR_CPU0_AC36  POWER  = PVDDCR_CPU0_P1
  AC40  VDDCR_CPU0_AC40  POWER  = PVDDCR_CPU0_P1
  AC41  VDDCR_CPU0_AC41  POWER  = PVDDCR_CPU0_P1
  AC42  VSS_AC42  POWER  = GND
  AC43  G0_TXP5  OUT  = GMI_CPU1_G0_CPU0_G2_TX_DP<10>
  AC44  G0_TXN5  OUT  = GMI_CPU1_G0_CPU0_G2_TX_DN<10>
  AC45  VSS_AC45  POWER  = GND
  AC46  G0_TXP8  OUT  = GMI_CPU1_G0_CPU0_G2_TX_DP<7>
  AC47  G0_TXN8  OUT  = GMI_CPU1_G0_CPU0_G2_TX_DN<7>
  AC48  VSS_AC48  POWER  = GND
  AC49  G0_TXP11  OUT  = GMI_CPU1_G0_CPU0_G2_TX_DP<4>
  AC50  G0_TXN11  OUT  = GMI_CPU1_G0_CPU0_G2_TX_DN<4>
  AC51  VSS_AC51  POWER  = GND
  AC52  G0_TXP14  OUT  = GMI_CPU1_G0_CPU0_G2_TX_DP<1>
  AC53  G0_TXN14  OUT  = GMI_CPU1_G0_CPU0_G2_TX_DN<1>
  AC54  VSS_AC54  POWER  = GND
  AC55  MCA_DATA23  BI  = M_C_CPU1_SA_DQ<23>
  AC56  VSS_AC56  POWER  = GND
  AC57  MCA_DATA24  BI  = M_C_CPU1_SA_DQ<24>
  AC58  VDDIO_AC58  POWER  = PVDDIO_P1
  AC59  MDA_DATA23  BI  = M_D_CPU1_SA_DQ<23>
  AC60  MDA_DATA24  BI  = M_D_CPU1_SA_DQ<24>
  AC61  VSS_AC61  POWER  = GND
  AC62  MBA_DATA23  BI  = M_B_CPU1_SA_DQ<23>
  AC63  VSS_AC63  POWER  = GND
  AC64  MBA_DATA24  BI  = M_B_CPU1_SA_DQ<24>
  AC65  VDDIO_AC65  POWER  = PVDDIO_P1
  AC66  MFA_DATA23  BI  = M_F_CPU1_SA_DQ<23>
  AC67  MFA_DATA24  BI  = M_F_CPU1_SA_DQ<24>
  AC68  VSS_AC68  POWER  = GND
  AC69  MEA_DATA23  BI  = M_E_CPU1_SA_DQ<23>
  AC70  VSS_AC70  POWER  = GND
  AC71  MEA_DATA24  BI  = M_E_CPU1_SA_DQ<24>
  AC72  VDDIO_AC72  POWER  = PVDDIO_P1
  AC73  MAA_DATA23  BI  = M_A_CPU1_SA_DQ<23>
  AC74  MAA_DATA24  BI  = M_A_CPU1_SA_DQ<24>
  AC75  VSS_AC75  POWER  = GND
  AD2  MGA_DATA26  BI  = M_G_CPU1_SA_DQ<26>
  AD3  VSS_AD3  POWER  = GND
  AD4  MGA_DATA25  BI  = M_G_CPU1_SA_DQ<25>
  AD5  VSS_AD5  POWER  = GND
  AD6  MKA_DATA26  BI  = M_K_CPU1_SA_DQ<26>
  AD7  MKA_DATA25  BI  = M_K_CPU1_SA_DQ<25>
  AD8  VSS_AD8  POWER  = GND
  AD9  MLA_DATA26  BI  = M_L_CPU1_SA_DQ<26>
  AD10  VSS_AD10  POWER  = GND
  AD11  MLA_DATA25  BI  = M_L_CPU1_SA_DQ<25>
  AD12  VSS_AD12  POWER  = GND
  AD13  MHA_DATA26  BI  = M_H_CPU1_SA_DQ<26>
  AD14  MHA_DATA25  BI  = M_H_CPU1_SA_DQ<25>
  AD15  VSS_AD15  POWER  = GND
  AD16  MJA_DATA26  BI  = M_J_CPU1_SA_DQ<26>
  AD17  VSS_AD17  POWER  = GND
  AD18  MJA_DATA25  BI  = M_J_CPU1_SA_DQ<25>
  AD19  VSS_AD19  POWER  = GND
  AD20  MIA_DATA26  BI  = M_I_CPU1_SA_DQ<26>
  AD21  MIA_DATA25  BI  = M_I_CPU1_SA_DQ<25>
  AD22  VDDCR_SOC_AD22  POWER  = PVDDCR_SOC_P1
  AD23  VSS_AD23  POWER  = GND
  AD24  VSS_AD24  POWER  = GND
  AD25  VSS_AD25  POWER  = GND
  AD26  VSS_AD26  POWER  = GND
  AD27  VSS_AD27  POWER  = GND
  AD28  VSS_AD28  POWER  = GND
  AD29  VSS_AD29  POWER  = GND
  AD30  VSS_AD30  POWER  = GND
  AD31  VSS_AD31  POWER  = GND
  AD32  VSS_AD32  POWER  = GND
  AD33  VSS_AD33  POWER  = GND
  AD34  VSS_AD34  POWER  = GND
  AD35  G2_RXN14  IN  = GMI_CPU0_G0_CPU1_G2_TX_DN<1>
  AD36  G2_RXP14  IN  = GMI_CPU0_G0_CPU1_G2_TX_DP<1>
  AD37  VSS_AD37  POWER  = GND
  AD39  VSS_AD39  POWER  = GND
  AD40  G0_TXP1  OUT  = GMI_CPU1_G0_CPU0_G2_TX_DP<14>
  AD41  G0_TXN1  OUT  = GMI_CPU1_G0_CPU0_G2_TX_DN<14>
  AD42  VSS_AD42  POWER  = GND
  AD43  VSS_AD43  POWER  = GND
  AD44  VSS_AD44  POWER  = GND
  AD45  VSS_AD45  POWER  = GND
  AD46  VSS_AD46  POWER  = GND
  AD47  VSS_AD47  POWER  = GND
  AD48  VSS_AD48  POWER  = GND
  AD49  VSS_AD49  POWER  = GND
  AD50  VSS_AD50  POWER  = GND
  AD51  VSS_AD51  POWER  = GND
  AD52  VSS_AD52  POWER  = GND
  AD53  VSS_AD53  POWER  = GND
  AD54  VDDIO_AD54  POWER  = PVDDIO_P1
  AD55  MCA_DATA25  BI  = M_C_CPU1_SA_DQ<25>
  AD56  MCA_DATA26  BI  = M_C_CPU1_SA_DQ<26>
  AD57  VSS_AD57  POWER  = GND
  AD58  MDA_DATA25  BI  = M_D_CPU1_SA_DQ<25>
  AD59  VSS_AD59  POWER  = GND
  AD60  MDA_DATA26  BI  = M_D_CPU1_SA_DQ<26>
  AD61  VSS_AD61  POWER  = GND
  AD62  MBA_DATA25  BI  = M_B_CPU1_SA_DQ<25>
  AD63  MBA_DATA26  BI  = M_B_CPU1_SA_DQ<26>
  AD64  VSS_AD64  POWER  = GND
  AD65  MFA_DATA25  BI  = M_F_CPU1_SA_DQ<25>
  AD66  VSS_AD66  POWER  = GND
